# S9S_MB_2U (Grand Teton) — schematic netlist excerpt (pin names and nets, part order shuffled) for the footprints in the layout excerpt that follows; sources: Cadence DE-HDL packaged netlist, KiCad conversion of 03242023_DA0F0TMBIJ0_F0T_Motherboard_J_brd_V01_OCP.brd

PC245_P0_7  Q_CAP  22UF 4V 20% X6S  pkg C0805  page 270 : A = PVCCIN_CPU0 ; B = GND
C540  Q_CAP  0.1UF 25V 10% X7R  pkg 0402  page 133 : A = P3V3_AUX ; B = GND
C1282  Q_CAP  0.1UF 25V 10% X7R  pkg 0402  page 191 : A = P3V3_E1S_0 ; B = GND

(kicad_pcb
	(version 20260206)
	(generator "pcbnew")
	(generator_version "10.0")
	(general
		(thickness 1.6)
		(legacy_teardrops no)
	)
	(paper "A4")
	(title_block
		(title "03242023_DA0F0TMBIJ0_F0T_Motherboard_J_brd_V01_OCP.brd")
		(comment 1 "Grand Teton / footprints 4673-4675 of 6105")
	)
	(layers
		(0 "F.Cu" signal "TOP")
		(4 "In1.Cu" signal "GND")
		(6 "In2.Cu" signal "IN1")
		(8 "In3.Cu" signal "GND1")
		(10 "In4.Cu" signal "IN2")
		(12 "In5.Cu" signal "GND2")
		(14 "In6.Cu" signal "IN3")
		(16 "In7.Cu" signal "GND3")
		(18 "In8.Cu" signal "VCC")
		(20 "In9.Cu" signal "VCC1")
		(22 "In10.Cu" signal "GND4")
		(24 "In11.Cu" signal "IN4")
		(26 "In12.Cu" signal "GND5")
		(28 "In13.Cu" signal "IN5")
		(30 "In14.Cu" signal "GND6")
		(32 "In15.Cu" signal "IN6")
		(34 "In16.Cu" signal "GND7")
		(2 "B.Cu" signal "BOTTOM")
		(9 "F.Adhes" user "F.Adhesive")
		(11 "B.Adhes" user "B.Adhesive")
		(13 "F.Paste" user "Package Geometry/Pastemask Top")
		(15 "B.Paste" user "Package Geometry/Pastemask Bottom")
		(5 "F.SilkS" user "Ref Des/Silkscreen Top")
		(7 "B.SilkS" user "Ref Des/Silkscreen Bottom")
		(1 "F.Mask" user "Board Geometry/Soldermask Top")
		(3 "B.Mask" user "Board Geometry/Soldermask Bottom")
		(17 "Dwgs.User" user "User.Drawings")
		(19 "Cmts.User" user "User.Comments")
		(21 "Eco1.User" user "User.Eco1")
		(23 "Eco2.User" user "User.Eco2")
		(25 "Edge.Cuts" user "Board Geometry/Outline")
		(27 "Margin" user)
		(31 "F.CrtYd" user "Package Geometry/Place Bound Top")
		(29 "B.CrtYd" user "Package Geometry/Place Bound Bottom")
		(35 "F.Fab" user "Ref Des/Assembly Top")
		(33 "B.Fab" user "Ref Des/Assembly Bottom")
	)
	(footprint ""
		(layer "B.Cu")
		(at 236.67593 -49.120044)
		(property "Reference" "C1282"
			(at 0 0 0)
			(layer "B.SilkS")
			(hide yes)
			(effects
				(font
					(size 1.27 1.27)
				)
				(justify mirror)
			)
		)
		(property "Value" ""
			(at 0 0 0)
			(layer "B.Fab")
			(effects
				(font
					(size 1.27 1.27)
				)
				(justify mirror)
			)
		)
		(duplicate_pad_numbers_are_jumpers no)
		(fp_line
			(start -0.7874 -0.4064)
			(end -0.7874 0.4064)
			(stroke
				(width 0.1524)
				(type default)
			)
			(layer "B.SilkS")
		)
		(fp_line
			(start -0.7874 0.4064)
			(end 0.7874 0.4064)
			(stroke
				(width 0.1524)
				(type default)
			)
			(layer "B.SilkS")
		)
		(fp_line
			(start 0.7874 -0.4064)
			(end -0.7874 -0.4064)
			(stroke
				(width 0.1524)
				(type default)
			)
			(layer "B.SilkS")
		)
		(fp_line
			(start 0.7874 0.4064)
			(end 0.7874 -0.4064)
			(stroke
				(width 0.1524)
				(type default)
			)
			(layer "B.SilkS")
		)
		(fp_line
			(start -0.67945 -0.3048)
			(end -0.67945 0.3048)
			(stroke
				(width 0.1)
				(type default)
			)
			(layer "B.Fab")
		)
		(fp_line
			(start -0.67945 0.3048)
			(end -0.120396 0.3048)
			(stroke
				(width 0.1)
				(type default)
			)
			(layer "B.Fab")
		)
		(fp_line
			(start -0.12065 -0.3048)
			(end -0.67945 -0.3048)
			(stroke
				(width 0.1)
				(type default)
			)
			(layer "B.Fab")
		)
		(fp_line
			(start -0.12065 -0.2794)
			(end -0.12065 -0.3048)
			(stroke
				(width 0.1)
				(type default)
			)
			(layer "B.Fab")
		)
		(fp_line
			(start -0.120396 0.2794)
			(end 0.12065 0.2794)
			(stroke
				(width 0.1)
				(type default)
			)
			(layer "B.Fab")
		)
		(fp_line
			(start -0.120396 0.3048)
			(end -0.120396 0.2794)
			(stroke
				(width 0.1)
				(type default)
			)
			(layer "B.Fab")
		)
		(fp_line
			(start 0.12065 -0.305054)
			(end 0.12065 -0.2794)
			(stroke
				(width 0.1)
				(type default)
			)
			(layer "B.Fab")
		)
		(fp_line
			(start 0.12065 -0.2794)
			(end -0.12065 -0.2794)
			(stroke
				(width 0.1)
				(type default)
			)
			(layer "B.Fab")
		)
		(fp_line
			(start 0.12065 0.2794)
			(end 0.12065 0.3048)
			(stroke
				(width 0.1)
				(type default)
			)
			(layer "B.Fab")
		)
		(fp_line
			(start 0.12065 0.3048)
			(end 0.67945 0.3048)
			(stroke
				(width 0.1)
				(type default)
			)
			(layer "B.Fab")
		)
		(fp_line
			(start 0.67945 -0.305054)
			(end 0.12065 -0.305054)
			(stroke
				(width 0.1)
				(type default)
			)
			(layer "B.Fab")
		)
		(fp_line
			(start 0.67945 0.3048)
			(end 0.67945 -0.305054)
			(stroke
				(width 0.1)
				(type default)
			)
			(layer "B.Fab")
		)
		(pad "1" smd circle
			(at 0.40005 0 180)
			(size 0 0)
			(layers "B.Cu" "B.Mask" "B.Paste")
			(net "P3V3_E1S_0")
		)
		(pad "2" smd circle
			(at -0.40005 0 180)
			(size 0 0)
			(layers "B.Cu" "B.Mask" "B.Paste")
			(net "GND")
		)
	)
	(footprint ""
		(layer "B.Cu")
		(at 209.794856 -194.136264)
		(property "Reference" "C540"
			(at 0 0 0)
			(layer "B.SilkS")
			(hide yes)
			(effects
				(font
					(size 1.27 1.27)
				)
				(justify mirror)
			)
		)
		(property "Value" ""
			(at 0 0 0)
			(layer "B.Fab")
			(effects
				(font
					(size 1.27 1.27)
				)
				(justify mirror)
			)
		)
		(duplicate_pad_numbers_are_jumpers no)
		(fp_line
			(start -0.7874 -0.4064)
			(end -0.7874 0.4064)
			(stroke
				(width 0.1524)
				(type default)
			)
			(layer "B.SilkS")
		)
		(fp_line
			(start -0.7874 0.4064)
			(end 0.7874 0.4064)
			(stroke
				(width 0.1524)
				(type default)
			)
			(layer "B.SilkS")
		)
		(fp_line
			(start 0.7874 -0.4064)
			(end -0.7874 -0.4064)
			(stroke
				(width 0.1524)
				(type default)
			)
			(layer "B.SilkS")
		)
		(fp_line
			(start 0.7874 0.4064)
			(end 0.7874 -0.4064)
			(stroke
				(width 0.1524)
				(type default)
			)
			(layer "B.SilkS")
		)
		(fp_line
			(start -0.67945 -0.3048)
			(end -0.67945 0.3048)
			(stroke
				(width 0.1)
				(type default)
			)
			(layer "B.Fab")
		)
		(fp_line
			(start -0.67945 0.3048)
			(end -0.120396 0.3048)
			(stroke
				(width 0.1)
				(type default)
			)
			(layer "B.Fab")
		)
		(fp_line
			(start -0.12065 -0.3048)
			(end -0.67945 -0.3048)
			(stroke
				(width 0.1)
				(type default)
			)
			(layer "B.Fab")
		)
		(fp_line
			(start -0.12065 -0.2794)
			(end -0.12065 -0.3048)
			(stroke
				(width 0.1)
				(type default)
			)
			(layer "B.Fab")
		)
		(fp_line
			(start -0.120396 0.2794)
			(end 0.12065 0.2794)
			(stroke
				(width 0.1)
				(type default)
			)
			(layer "B.Fab")
		)
		(fp_line
			(start -0.120396 0.3048)
			(end -0.120396 0.2794)
			(stroke
				(width 0.1)
				(type default)
			)
			(layer "B.Fab")
		)
		(fp_line
			(start 0.12065 -0.305054)
			(end 0.12065 -0.2794)
			(stroke
				(width 0.1)
				(type default)
			)
			(layer "B.Fab")
		)
		(fp_line
			(start 0.12065 -0.2794)
			(end -0.12065 -0.2794)
			(stroke
				(width 0.1)
				(type default)
			)
			(layer "B.Fab")
		)
		(fp_line
			(start 0.12065 0.2794)
			(end 0.12065 0.3048)
			(stroke
				(width 0.1)
				(type default)
			)
			(layer "B.Fab")
		)
		(fp_line
			(start 0.12065 0.3048)
			(end 0.67945 0.3048)
			(stroke
				(width 0.1)
				(type default)
			)
			(layer "B.Fab")
		)
		(fp_line
			(start 0.67945 -0.305054)
			(end 0.12065 -0.305054)
			(stroke
				(width 0.1)
				(type default)
			)
			(layer "B.Fab")
		)
		(fp_line
			(start 0.67945 0.3048)
			(end 0.67945 -0.305054)
			(stroke
				(width 0.1)
				(type default)
			)
			(layer "B.Fab")
		)
		(pad "1" smd circle
			(at 0.40005 0 180)
			(size 0 0)
			(layers "B.Cu" "B.Mask" "B.Paste")
			(net "P3V3_AUX")
		)
		(pad "2" smd circle
			(at -0.40005 0 180)
			(size 0 0)
			(layers "B.Cu" "B.Mask" "B.Paste")
			(net "GND")
		)
	)
	(footprint ""
		(layer "B.Cu")
		(at 329.367388 -333.62138 -90)
		(property "Reference" "PC245_P0_7"
			(at 0 0 90)
			(layer "B.SilkS")
			(hide yes)
			(effects
				(font
					(size 1.27 1.27)
				)
				(justify mirror)
			)
		)
		(property "Value" ""
			(at 0 0 90)
			(layer "B.Fab")
			(effects
				(font
					(size 1.27 1.27)
				)
				(justify mirror)
			)
		)
		(duplicate_pad_numbers_are_jumpers no)
		(fp_line
			(start -1.524 0.762)
			(end 1.524 0.762)
			(stroke
				(width 0.1524)
				(type default)
			)
			(layer "B.SilkS")
		)
		(fp_line
			(start 1.524 0.762)
			(end 1.524 -0.762)
			(stroke
				(width 0.1524)
				(type default)
			)
			(layer "B.SilkS")
		)
		(fp_line
			(start -1.524 -0.762)
			(end -1.524 0.762)
			(stroke
				(width 0.1524)
				(type default)
			)
			(layer "B.SilkS")
		)
		(fp_line
			(start 1.524 -0.762)
			(end -1.524 -0.762)
			(stroke
				(width 0.1524)
				(type default)
			)
			(layer "B.SilkS")
		)
		(fp_line
			(start -1.1049 0.724916)
			(end -1.1049 -0.724916)
			(stroke
				(width 0.1)
				(type default)
			)
			(layer "B.Fab")
		)
		(fp_line
			(start 1.1049 0.724916)
			(end -1.1049 0.724916)
			(stroke
				(width 0.1)
				(type default)
			)
			(layer "B.Fab")
		)
		(fp_line
			(start -1.1049 -0.724916)
			(end 1.1049 -0.724916)
			(stroke
				(width 0.1)
				(type default)
			)
			(layer "B.Fab")
		)
		(fp_line
			(start 1.1049 -0.724916)
			(end 1.1049 0.724916)
			(stroke
				(width 0.1)
				(type default)
			)
			(layer "B.Fab")
		)
		(pad "1" smd rect
			(at 0.889 0 270)
			(size 1.016 1.27)
			(layers "B.Cu" "B.Mask" "B.Paste")
			(net "PVCCIN_CPU0")
		)
		(pad "2" smd rect
			(at -0.889 0 270)
			(size 1.016 1.27)
			(layers "B.Cu" "B.Mask" "B.Paste")
			(net "GND")
		)
	)
)
